(kicad_pcb
	(version 20260206)
	(generator "pcbnew")
	(generator_version "10.0")
	(general
		(thickness 1.6)
		(legacy_teardrops no)
	)
	(paper "A4")
	(title_block
		(title "03242023_DA0F0TMBIJ0_F0T_Motherboard_J_brd_V01_OCP.brd")
		(comment 1 "Grand Teton / footprints 46-53 of 6105")
	)
	(layers
		(0 "F.Cu" signal "TOP")
		(4 "In1.Cu" signal "GND")
		(6 "In2.Cu" signal "IN1")
		(8 "In3.Cu" signal "GND1")
		(10 "In4.Cu" signal "IN2")
		(12 "In5.Cu" signal "GND2")
		(14 "In6.Cu" signal "IN3")
		(16 "In7.Cu" signal "GND3")
		(18 "In8.Cu" signal "VCC")
		(20 "In9.Cu" signal "VCC1")
		(22 "In10.Cu" signal "GND4")
		(24 "In11.Cu" signal "IN4")
		(26 "In12.Cu" signal "GND5")
		(28 "In13.Cu" signal "IN5")
		(30 "In14.Cu" signal "GND6")
		(32 "In15.Cu" signal "IN6")
		(34 "In16.Cu" signal "GND7")
		(2 "B.Cu" signal "BOTTOM")
		(9 "F.Adhes" user "F.Adhesive")
		(11 "B.Adhes" user "B.Adhesive")
		(13 "F.Paste" user "Package Geometry/Pastemask Top")
		(15 "B.Paste" user "Package Geometry/Pastemask Bottom")
		(5 "F.SilkS" user "Ref Des/Silkscreen Top")
		(7 "B.SilkS" user "Ref Des/Silkscreen Bottom")
		(1 "F.Mask" user "Board Geometry/Soldermask Top")
		(3 "B.Mask" user "Board Geometry/Soldermask Bottom")
		(17 "Dwgs.User" user "User.Drawings")
		(19 "Cmts.User" user "User.Comments")
		(21 "Eco1.User" user "User.Eco1")
		(23 "Eco2.User" user "User.Eco2")
		(25 "Edge.Cuts" user "Board Geometry/Outline")
		(27 "Margin" user)
		(31 "F.CrtYd" user "Package Geometry/Place Bound Top")
		(29 "B.CrtYd" user "Package Geometry/Place Bound Bottom")
		(35 "F.Fab" user "Ref Des/Assembly Top")
		(33 "B.Fab" user "Ref Des/Assembly Bottom")
	)
	(footprint ""
		(layer "F.Cu")
		(at 121.475754 -408.517344 -90)
		(property "Reference" "C1516"
			(at 0 0 270)
			(layer "F.SilkS")
			(hide yes)
			(effects
				(font
					(size 1.27 1.27)
				)
			)
		)
		(property "Value" ""
			(at 0 0 270)
			(layer "F.Fab")
			(effects
				(font
					(size 1.27 1.27)
				)
			)
		)
		(duplicate_pad_numbers_are_jumpers no)
		(fp_line
			(start -0.299974 0.150114)
			(end -0.299974 -0.150114)
			(stroke
				(width 0.1)
				(type default)
			)
			(layer "F.Fab")
		)
		(fp_line
			(start 0.299974 0.150114)
			(end -0.299974 0.150114)
			(stroke
				(width 0.1)
				(type default)
			)
			(layer "F.Fab")
		)
		(fp_line
			(start -0.299974 -0.150114)
			(end 0.299974 -0.150114)
			(stroke
				(width 0.1)
				(type default)
			)
			(layer "F.Fab")
		)
		(fp_line
			(start 0.299974 -0.150114)
			(end 0.299974 0.150114)
			(stroke
				(width 0.1)
				(type default)
			)
			(layer "F.Fab")
		)
		(pad "1" smd rect
			(at -0.2667 0 270)
			(size 0.3048 0.381)
			(layers "F.Cu" "F.Mask" "F.Paste")
			(net "P5E_CPU1_PE3_TX_C_DN<15>")
		)
		(pad "2" smd rect
			(at 0.2667 0 270)
			(size 0.3048 0.381)
			(layers "F.Cu" "F.Mask" "F.Paste")
			(net "P5E_CPU1_PE3_TX_DN<15>")
		)
	)
	(footprint ""
		(layer "F.Cu")
		(at 392.763248 -162.360864 -90)
		(property "Reference" "R994"
			(at 0 0 270)
			(layer "F.SilkS")
			(hide yes)
			(effects
				(font
					(size 1.27 1.27)
				)
			)
		)
		(property "Value" ""
			(at 0 0 270)
			(layer "F.Fab")
			(effects
				(font
					(size 1.27 1.27)
				)
			)
		)
		(duplicate_pad_numbers_are_jumpers no)
		(fp_line
			(start -0.7874 0.4064)
			(end -0.7874 -0.4064)
			(stroke
				(width 0.1524)
				(type default)
			)
			(layer "F.SilkS")
		)
		(fp_line
			(start 0.7874 0.4064)
			(end -0.7874 0.4064)
			(stroke
				(width 0.1524)
				(type default)
			)
			(layer "F.SilkS")
		)
		(fp_line
			(start -0.7874 -0.4064)
			(end 0.7874 -0.4064)
			(stroke
				(width 0.1524)
				(type default)
			)
			(layer "F.SilkS")
		)
		(fp_line
			(start 0.7874 -0.4064)
			(end 0.7874 0.4064)
			(stroke
				(width 0.1524)
				(type default)
			)
			(layer "F.SilkS")
		)
		(fp_line
			(start -0.67945 0.3048)
			(end -0.67945 -0.305054)
			(stroke
				(width 0.1)
				(type default)
			)
			(layer "F.Fab")
		)
		(fp_line
			(start -0.12065 0.3048)
			(end -0.67945 0.3048)
			(stroke
				(width 0.1)
				(type default)
			)
			(layer "F.Fab")
		)
		(fp_line
			(start 0.120396 0.3048)
			(end 0.120396 0.2794)
			(stroke
				(width 0.1)
				(type default)
			)
			(layer "F.Fab")
		)
		(fp_line
			(start 0.67945 0.3048)
			(end 0.120396 0.3048)
			(stroke
				(width 0.1)
				(type default)
			)
			(layer "F.Fab")
		)
		(fp_line
			(start -0.12065 0.2794)
			(end -0.12065 0.3048)
			(stroke
				(width 0.1)
				(type default)
			)
			(layer "F.Fab")
		)
		(fp_line
			(start 0.120396 0.2794)
			(end -0.12065 0.2794)
			(stroke
				(width 0.1)
				(type default)
			)
			(layer "F.Fab")
		)
		(fp_line
			(start -0.12065 -0.2794)
			(end 0.12065 -0.2794)
			(stroke
				(width 0.1)
				(type default)
			)
			(layer "F.Fab")
		)
		(fp_line
			(start 0.12065 -0.2794)
			(end 0.12065 -0.3048)
			(stroke
				(width 0.1)
				(type default)
			)
			(layer "F.Fab")
		)
		(fp_line
			(start 0.12065 -0.3048)
			(end 0.67945 -0.3048)
			(stroke
				(width 0.1)
				(type default)
			)
			(layer "F.Fab")
		)
		(fp_line
			(start 0.67945 -0.3048)
			(end 0.67945 0.3048)
			(stroke
				(width 0.1)
				(type default)
			)
			(layer "F.Fab")
		)
		(fp_line
			(start -0.67945 -0.305054)
			(end -0.12065 -0.305054)
			(stroke
				(width 0.1)
				(type default)
			)
			(layer "F.Fab")
		)
		(fp_line
			(start -0.12065 -0.305054)
			(end -0.12065 -0.2794)
			(stroke
				(width 0.1)
				(type default)
			)
			(layer "F.Fab")
		)
		(pad "1" smd circle
			(at -0.40005 0 270)
			(size 0 0)
			(layers "F.Cu" "F.Mask" "F.Paste")
			(net "SMB_S3M_CPU0_SDA")
		)
		(pad "2" smd circle
			(at 0.40005 0 270)
			(size 0 0)
			(layers "F.Cu" "F.Mask" "F.Paste")
			(net "SMB_S3M_CPU0_R_SDA")
		)
	)
	(footprint ""
		(layer "F.Cu")
		(at 399.88109 -402.371052 -90)
		(property "Reference" "C952"
			(at 0 0 270)
			(layer "F.SilkS")
			(hide yes)
			(effects
				(font
					(size 1.27 1.27)
				)
			)
		)
		(property "Value" ""
			(at 0 0 270)
			(layer "F.Fab")
			(effects
				(font
					(size 1.27 1.27)
				)
			)
		)
		(duplicate_pad_numbers_are_jumpers no)
		(fp_line
			(start -0.299974 0.150114)
			(end -0.299974 -0.150114)
			(stroke
				(width 0.1)
				(type default)
			)
			(layer "F.Fab")
		)
		(fp_line
			(start 0.299974 0.150114)
			(end -0.299974 0.150114)
			(stroke
				(width 0.1)
				(type default)
			)
			(layer "F.Fab")
		)
		(fp_line
			(start -0.299974 -0.150114)
			(end 0.299974 -0.150114)
			(stroke
				(width 0.1)
				(type default)
			)
			(layer "F.Fab")
		)
		(fp_line
			(start 0.299974 -0.150114)
			(end 0.299974 0.150114)
			(stroke
				(width 0.1)
				(type default)
			)
			(layer "F.Fab")
		)
		(pad "1" smd rect
			(at -0.2667 0 270)
			(size 0.3048 0.381)
			(layers "F.Cu" "F.Mask" "F.Paste")
			(net "P5E_CPU0_PE2_TX_C_DN<6>")
		)
		(pad "2" smd rect
			(at 0.2667 0 270)
			(size 0.3048 0.381)
			(layers "F.Cu" "F.Mask" "F.Paste")
			(net "P5E_CPU0_PE2_TX_DN<6>")
		)
	)
	(footprint ""
		(layer "F.Cu")
		(at 135.86841 -41.840404)
		(property "Reference" "U259"
			(at -0.31496 -1.85547 0)
			(unlocked yes)
			(layer "F.SilkS")
			(effects
				(font
					(size 0.7874 0.5842)
					(thickness 0.1524)
				)
			)
		)
		(property "Value" ""
			(at 0 0 0)
			(layer "F.Fab")
			(effects
				(font
					(size 1.27 1.27)
				)
			)
		)
		(duplicate_pad_numbers_are_jumpers no)
		(fp_line
			(start -1.7272 1.1176)
			(end -1.7272 -1.1176)
			(stroke
				(width 0.1524)
				(type default)
			)
			(layer "F.SilkS")
		)
		(fp_line
			(start -0.254 -1.1176)
			(end -1.7272 -1.1176)
			(stroke
				(width 0.1524)
				(type default)
			)
			(layer "F.SilkS")
		)
		(fp_line
			(start 0 -0.7366)
			(end -0.254 -1.1176)
			(stroke
				(width 0.1524)
				(type default)
			)
			(layer "F.SilkS")
		)
		(fp_line
			(start 0.254 -1.1176)
			(end 0 -0.7366)
			(stroke
				(width 0.1524)
				(type default)
			)
			(layer "F.SilkS")
		)
		(fp_line
			(start 1.7272 -1.1176)
			(end 0.254 -1.1176)
			(stroke
				(width 0.1524)
				(type default)
			)
			(layer "F.SilkS")
		)
		(fp_line
			(start 1.7272 -1.1176)
			(end 1.7272 1.1176)
			(stroke
				(width 0.1524)
				(type default)
			)
			(layer "F.SilkS")
		)
		(fp_line
			(start 1.7272 1.1176)
			(end -1.7272 1.1176)
			(stroke
				(width 0.1524)
				(type default)
			)
			(layer "F.SilkS")
		)
		(fp_poly
			(pts
				(xy -2.7178 -0.268986) (xy -2.7178 -1.030986) (xy -1.9558 -0.649986)
			)
			(stroke
				(width 0)
				(type default)
			)
			(fill yes)
			(layer "F.SilkS")
		)
		(fp_line
			(start -1.5748 -1.1176)
			(end -1.5748 1.1176)
			(stroke
				(width 0.1)
				(type default)
			)
			(layer "F.Fab")
		)
		(fp_line
			(start -1.5748 1.1176)
			(end 1.5748 1.1176)
			(stroke
				(width 0.1)
				(type default)
			)
			(layer "F.Fab")
		)
		(fp_line
			(start 1.5748 -1.1176)
			(end -1.5748 -1.1176)
			(stroke
				(width 0.1)
				(type default)
			)
			(layer "F.Fab")
		)
		(fp_line
			(start 1.5748 1.1176)
			(end 1.5748 -1.1176)
			(stroke
				(width 0.1)
				(type default)
			)
			(layer "F.Fab")
		)
		(fp_poly
			(pts
				(xy -1.9558 -0.649986) (xy -2.7178 -0.268986) (xy -2.7178 -1.030986)
			)
			(stroke
				(width 0)
				(type default)
			)
			(fill yes)
			(layer "F.Fab")
		)
		(pad "1" smd rect
			(at -0.999998 -0.649986 270)
			(size 0.3556 1.1176)
			(layers "F.Cu" "F.Mask" "F.Paste")
			(net "M2_SSD0_CLKREQ_EN_N")
		)
		(pad "2" smd rect
			(at -0.999998 0 270)
			(size 0.3556 1.1176)
			(layers "F.Cu" "F.Mask" "F.Paste")
			(net "GND")
		)
		(pad "3" smd rect
			(at -0.999998 0.649986 270)
			(size 0.3556 1.1176)
			(layers "F.Cu" "F.Mask" "F.Paste")
			(net "RST_PCIE_PCH_DEV_PERST_M2_R_N")
		)
		(pad "4" smd rect
			(at 0.999998 0.649986 270)
			(size 0.3556 1.1176)
			(layers "F.Cu" "F.Mask" "F.Paste")
			(net "RST_PCIE_PCH_DEV_BUF_M2_0_PERST")
		)
		(pad "5" smd rect
			(at 0.999998 0 270)
			(size 0.3556 1.1176)
			(layers "F.Cu" "F.Mask" "F.Paste")
			(net "P3V3_AUX")
		)
		(pad "6" smd rect
			(at 0.999998 -0.649986 270)
			(size 0.3556 1.1176)
			(layers "F.Cu" "F.Mask" "F.Paste")
			(net "HDD_ACTIVITY_BUF")
		)
	)
	(footprint ""
		(layer "F.Cu")
		(at 277.61946 -93.741494)
		(property "Reference" "R713"
			(at 0 0 0)
			(layer "F.SilkS")
			(hide yes)
			(effects
				(font
					(size 1.27 1.27)
				)
			)
		)
		(property "Value" ""
			(at 0 0 0)
			(layer "F.Fab")
			(effects
				(font
					(size 1.27 1.27)
				)
			)
		)
		(duplicate_pad_numbers_are_jumpers no)
		(fp_line
			(start -0.7874 -0.4064)
			(end 0.7874 -0.4064)
			(stroke
				(width 0.1524)
				(type default)
			)
			(layer "F.SilkS")
		)
		(fp_line
			(start -0.7874 0.4064)
			(end -0.7874 -0.4064)
			(stroke
				(width 0.1524)
				(type default)
			)
			(layer "F.SilkS")
		)
		(fp_line
			(start 0.7874 -0.4064)
			(end 0.7874 0.4064)
			(stroke
				(width 0.1524)
				(type default)
			)
			(layer "F.SilkS")
		)
		(fp_line
			(start 0.7874 0.4064)
			(end -0.7874 0.4064)
			(stroke
				(width 0.1524)
				(type default)
			)
			(layer "F.SilkS")
		)
		(fp_line
			(start -0.67945 -0.305054)
			(end -0.12065 -0.305054)
			(stroke
				(width 0.1)
				(type default)
			)
			(layer "F.Fab")
		)
		(fp_line
			(start -0.67945 0.3048)
			(end -0.67945 -0.305054)
			(stroke
				(width 0.1)
				(type default)
			)
			(layer "F.Fab")
		)
		(fp_line
			(start -0.12065 -0.305054)
			(end -0.12065 -0.2794)
			(stroke
				(width 0.1)
				(type default)
			)
			(layer "F.Fab")
		)
		(fp_line
			(start -0.12065 -0.2794)
			(end 0.12065 -0.2794)
			(stroke
				(width 0.1)
				(type default)
			)
			(layer "F.Fab")
		)
		(fp_line
			(start -0.12065 0.2794)
			(end -0.12065 0.3048)
			(stroke
				(width 0.1)
				(type default)
			)
			(layer "F.Fab")
		)
		(fp_line
			(start -0.12065 0.3048)
			(end -0.67945 0.3048)
			(stroke
				(width 0.1)
				(type default)
			)
			(layer "F.Fab")
		)
		(fp_line
			(start 0.120396 0.2794)
			(end -0.12065 0.2794)
			(stroke
				(width 0.1)
				(type default)
			)
			(layer "F.Fab")
		)
		(fp_line
			(start 0.120396 0.3048)
			(end 0.120396 0.2794)
			(stroke
				(width 0.1)
				(type default)
			)
			(layer "F.Fab")
		)
		(fp_line
			(start 0.12065 -0.3048)
			(end 0.67945 -0.3048)
			(stroke
				(width 0.1)
				(type default)
			)
			(layer "F.Fab")
		)
		(fp_line
			(start 0.12065 -0.2794)
			(end 0.12065 -0.3048)
			(stroke
				(width 0.1)
				(type default)
			)
			(layer "F.Fab")
		)
		(fp_line
			(start 0.67945 -0.3048)
			(end 0.67945 0.3048)
			(stroke
				(width 0.1)
				(type default)
			)
			(layer "F.Fab")
		)
		(fp_line
			(start 0.67945 0.3048)
			(end 0.120396 0.3048)
			(stroke
				(width 0.1)
				(type default)
			)
			(layer "F.Fab")
		)
		(pad "1" smd circle
			(at -0.40005 0)
			(size 0 0)
			(layers "F.Cu" "F.Mask" "F.Paste")
			(net "P3V3_AUX")
		)
		(pad "2" smd circle
			(at 0.40005 0)
			(size 0 0)
			(layers "F.Cu" "F.Mask" "F.Paste")
			(net "MB_FRU_ADDR2")
		)
	)
	(footprint ""
		(layer "F.Cu")
		(at 421.292528 -346.017342)
		(property "Reference" "PC1183"
			(at 0 0 0)
			(layer "F.SilkS")
			(hide yes)
			(effects
				(font
					(size 1.27 1.27)
				)
			)
		)
		(property "Value" ""
			(at 0 0 0)
			(layer "F.Fab")
			(effects
				(font
					(size 1.27 1.27)
				)
			)
		)
		(duplicate_pad_numbers_are_jumpers no)
		(fp_line
			(start 2.750058 0.999998)
			(end -2.750058 0.999998)
			(stroke
				(width 0.1524)
				(type default)
			)
			(layer "F.SilkS")
		)
		(fp_circle
			(center 0 0.999998)
			(end 2.750058 0.999998)
			(stroke
				(width 0.1524)
				(type default)
			)
			(fill no)
			(layer "F.SilkS")
		)
		(fp_poly
			(pts
				(arc
					(start 2.750058 0.999998)
					(mid 0 3.750056)
					(end -2.750058 0.999998)
				)
			)
			(stroke
				(width 0)
				(type default)
			)
			(fill yes)
			(layer "F.SilkS")
		)
		(fp_circle
			(center 0 0.999998)
			(end 2.750058 0.999998)
			(stroke
				(width 0.1)
				(type default)
			)
			(fill no)
			(layer "F.Fab")
		)
		(pad "1" thru_hole rect
			(at 0 0)
			(size 1.5748 1.5748)
			(drill 1.0668)
			(layers "*.Cu" "*.Mask")
			(remove_unused_layers no)
			(net "PVCCFA_EHV_FIVRA_CPU0")
			(clearance 0)
			(padstack
				(mode front_inner_back)
				(layer "Inner"
					(shape circle)
					(size 1.5748 1.5748)
					(clearance 0)
				)
				(layer "B.Cu"
					(shape rect)
					(size 1.5748 1.5748)
					(clearance 0)
				)
			)
		)
		(pad "2" thru_hole circle
			(at 0 1.999996)
			(size 1.5748 1.5748)
			(drill 1.0668)
			(layers "*.Cu" "*.Mask")
			(remove_unused_layers no)
			(net "GND")
			(clearance 0)
		)
	)
	(footprint ""
		(layer "F.Cu")
		(at 327.281032 -15.829534)
		(property "Reference" "C513"
			(at 0 0 0)
			(layer "F.SilkS")
			(hide yes)
			(effects
				(font
					(size 1.27 1.27)
				)
			)
		)
		(property "Value" ""
			(at 0 0 0)
			(layer "F.Fab")
			(effects
				(font
					(size 1.27 1.27)
				)
			)
		)
		(duplicate_pad_numbers_are_jumpers no)
		(fp_line
			(start -1.524 -0.762)
			(end 1.524 -0.762)
			(stroke
				(width 0.1524)
				(type default)
			)
			(layer "F.SilkS")
		)
		(fp_line
			(start -1.524 0.762)
			(end -1.524 -0.762)
			(stroke
				(width 0.1524)
				(type default)
			)
			(layer "F.SilkS")
		)
		(fp_line
			(start 1.524 -0.762)
			(end 1.524 0.762)
			(stroke
				(width 0.1524)
				(type default)
			)
			(layer "F.SilkS")
		)
		(fp_line
			(start 1.524 0.762)
			(end -1.524 0.762)
			(stroke
				(width 0.1524)
				(type default)
			)
			(layer "F.SilkS")
		)
		(fp_line
			(start -1.1049 -0.724916)
			(end -1.1049 0.724916)
			(stroke
				(width 0.1)
				(type default)
			)
			(layer "F.Fab")
		)
		(fp_line
			(start -1.1049 0.724916)
			(end 1.1049 0.724916)
			(stroke
				(width 0.1)
				(type default)
			)
			(layer "F.Fab")
		)
		(fp_line
			(start 1.1049 -0.724916)
			(end -1.1049 -0.724916)
			(stroke
				(width 0.1)
				(type default)
			)
			(layer "F.Fab")
		)
		(fp_line
			(start 1.1049 0.724916)
			(end 1.1049 -0.724916)
			(stroke
				(width 0.1)
				(type default)
			)
			(layer "F.Fab")
		)
		(pad "1" smd rect
			(at -0.889 0 180)
			(size 1.016 1.27)
			(layers "F.Cu" "F.Mask" "F.Paste")
			(net "PGPPA_AUX")
		)
		(pad "2" smd rect
			(at 0.889 0 180)
			(size 1.016 1.27)
			(layers "F.Cu" "F.Mask" "F.Paste")
			(net "GND")
		)
	)
	(footprint ""
		(layer "F.Cu")
		(at 437.242966 -121.632726)
		(property "Reference" "R2405"
			(at 0 0 0)
			(layer "F.SilkS")
			(hide yes)
			(effects
				(font
					(size 1.27 1.27)
				)
			)
		)
		(property "Value" ""
			(at 0 0 0)
			(layer "F.Fab")
			(effects
				(font
					(size 1.27 1.27)
				)
			)
		)
		(duplicate_pad_numbers_are_jumpers no)
		(fp_line
			(start -0.7874 -0.4064)
			(end 0.7874 -0.4064)
			(stroke
				(width 0.1524)
				(type default)
			)
			(layer "F.SilkS")
		)
		(fp_line
			(start -0.7874 0.4064)
			(end -0.7874 -0.4064)
			(stroke
				(width 0.1524)
				(type default)
			)
			(layer "F.SilkS")
		)
		(fp_line
			(start 0.7874 -0.4064)
			(end 0.7874 0.4064)
			(stroke
				(width 0.1524)
				(type default)
			)
			(layer "F.SilkS")
		)
		(fp_line
			(start 0.7874 0.4064)
			(end -0.7874 0.4064)
			(stroke
				(width 0.1524)
				(type default)
			)
			(layer "F.SilkS")
		)
		(fp_line
			(start -0.67945 -0.305054)
			(end -0.12065 -0.305054)
			(stroke
				(width 0.1)
				(type default)
			)
			(layer "F.Fab")
		)
		(fp_line
			(start -0.67945 0.3048)
			(end -0.67945 -0.305054)
			(stroke
				(width 0.1)
				(type default)
			)
			(layer "F.Fab")
		)
		(fp_line
			(start -0.12065 -0.305054)
			(end -0.12065 -0.2794)
			(stroke
				(width 0.1)
				(type default)
			)
			(layer "F.Fab")
		)
		(fp_line
			(start -0.12065 -0.2794)
			(end 0.12065 -0.2794)
			(stroke
				(width 0.1)
				(type default)
			)
			(layer "F.Fab")
		)
		(fp_line
			(start -0.12065 0.2794)
			(end -0.12065 0.3048)
			(stroke
				(width 0.1)
				(type default)
			)
			(layer "F.Fab")
		)
		(fp_line
			(start -0.12065 0.3048)
			(end -0.67945 0.3048)
			(stroke
				(width 0.1)
				(type default)
			)
			(layer "F.Fab")
		)
		(fp_line
			(start 0.120396 0.2794)
			(end -0.12065 0.2794)
			(stroke
				(width 0.1)
				(type default)
			)
			(layer "F.Fab")
		)
		(fp_line
			(start 0.120396 0.3048)
			(end 0.120396 0.2794)
			(stroke
				(width 0.1)
				(type default)
			)
			(layer "F.Fab")
		)
		(fp_line
			(start 0.12065 -0.3048)
			(end 0.67945 -0.3048)
			(stroke
				(width 0.1)
				(type default)
			)
			(layer "F.Fab")
		)
		(fp_line
			(start 0.12065 -0.2794)
			(end 0.12065 -0.3048)
			(stroke
				(width 0.1)
				(type default)
			)
			(layer "F.Fab")
		)
		(fp_line
			(start 0.67945 -0.3048)
			(end 0.67945 0.3048)
			(stroke
				(width 0.1)
				(type default)
			)
			(layer "F.Fab")
		)
		(fp_line
			(start 0.67945 0.3048)
			(end 0.120396 0.3048)
			(stroke
				(width 0.1)
				(type default)
			)
			(layer "F.Fab")
		)
		(pad "1" smd circle
			(at -0.40005 0)
			(size 0 0)
			(layers "F.Cu" "F.Mask" "F.Paste")
			(net "IRQ_PVCCD_CPU0_VRHOT_LVC3_R_N")
		)
		(pad "2" smd circle
			(at 0.40005 0)
			(size 0 0)
			(layers "F.Cu" "F.Mask" "F.Paste")
			(net "IRQ_PVCCD_CPU0_VRHOT_LVC3_N")
		)
	)
)
